(kicad_pcb
	(version 20241229)
	(generator "pcbnew")
	(generator_version "9.0")
	(general
		(thickness 1.62)
		(legacy_teardrops no)
	)
	(paper "A3")
	(title_block
		(title "COM Express 7 Baseboard")
		(date "2025-02-04")
		(rev "1.1.2")
		(company "Antmicro Ltd")
		(comment 1 "www.antmicro.com")
		(comment 9 "footprints 107-111 of 802")
	)
	(layers
		(0 "F.Cu" signal)
		(4 "In1.Cu" signal)
		(6 "In2.Cu" signal)
		(8 "In3.Cu" signal)
		(10 "In4.Cu" signal)
		(12 "In5.Cu" signal)
		(14 "In6.Cu" signal)
		(2 "B.Cu" signal)
		(9 "F.Adhes" user "F.Adhesive")
		(11 "B.Adhes" user "B.Adhesive")
		(13 "F.Paste" user)
		(15 "B.Paste" user)
		(5 "F.SilkS" user "F.Silkscreen")
		(7 "B.SilkS" user "B.Silkscreen")
		(1 "F.Mask" user)
		(3 "B.Mask" user)
		(17 "Dwgs.User" user "User.Drawings")
		(19 "Cmts.User" user "User.Comments")
		(21 "Eco1.User" user "User.Eco1")
		(23 "Eco2.User" user "User.Eco2")
		(25 "Edge.Cuts" user)
		(27 "Margin" user)
		(31 "F.CrtYd" user "F.Courtyard")
		(29 "B.CrtYd" user "B.Courtyard")
		(35 "F.Fab" user)
		(33 "B.Fab" user)
	)
	(footprint "antmicro-footprints:R_0402_1005Metric"
		(layer "F.Cu")
		(at 112.4 144.36 90)
		(descr "Resistor SMD 0402")
		(tags "resistor SMD 0402")
		(property "Reference" "R207"
			(at 0.8 0.4 90)
			(layer "F.SilkS")
			(effects
				(font
					(size 0.7 0.7)
					(thickness 0.15)
				)
				(justify left bottom)
			)
		)
		(property "Value" "R_1k_0402"
			(at -1.011843 1.772047 90)
			(layer "F.Fab")
			(effects
				(font
					(size 0.7 0.7)
					(thickness 0.15)
				)
				(justify left bottom)
			)
		)
		(property "Datasheet" "https://www.bourns.com/docs/product-datasheets/cr.pdf"
			(at 0 0 90)
			(layer "F.Fab")
			(hide yes)
			(effects
				(font
					(size 1.27 1.27)
					(thickness 0.15)
				)
			)
		)
		(property "Author" "Antmicro"
			(at 256.76 31.96 0)
			(layer "F.Fab")
			(hide yes)
			(effects
				(font
					(size 1 1)
					(thickness 0.15)
				)
			)
		)
		(property "License" "Apache-2.0"
			(at 256.76 31.96 0)
			(layer "F.Fab")
			(hide yes)
			(effects
				(font
					(size 1 1)
					(thickness 0.15)
				)
			)
		)
		(property "MPN" "CR0402-FX-1001GLF"
			(at 256.76 31.96 0)
			(layer "F.Fab")
			(hide yes)
			(effects
				(font
					(size 1 1)
					(thickness 0.15)
				)
			)
		)
		(property "Manufacturer" "Bourns"
			(at 256.76 31.96 0)
			(layer "F.Fab")
			(hide yes)
			(effects
				(font
					(size 1 1)
					(thickness 0.15)
				)
			)
		)
		(property "Public" "False"
			(at 256.76 31.96 0)
			(layer "F.Fab")
			(hide yes)
			(effects
				(font
					(size 1 1)
					(thickness 0.15)
				)
			)
		)
		(property "Tolerance" "1%"
			(at 256.76 31.96 0)
			(layer "F.Fab")
			(hide yes)
			(effects
				(font
					(size 1 1)
					(thickness 0.15)
				)
			)
		)
		(property "Val" "1k"
			(at 256.76 31.96 0)
			(layer "F.Fab")
			(hide yes)
			(effects
				(font
					(size 1 1)
					(thickness 0.15)
				)
			)
		)
		(sheetname "PCIe redriver")
		(sheetfile "pcie_redriver.kicad_sch")
		(attr smd dnp)
		(fp_rect
			(start -0.925 -0.47)
			(end 0.925 0.47)
			(stroke
				(width 0.05)
				(type default)
			)
			(fill no)
			(layer "F.CrtYd")
		)
		(fp_rect
			(start -0.5 -0.25)
			(end 0.5 0.25)
			(stroke
				(width 0.15)
				(type solid)
			)
			(fill no)
			(layer "F.Fab")
		)
		(pad "1" smd roundrect
			(at -0.48 0 90)
			(size 0.59 0.64)
			(layers "F.Cu" "F.Mask" "F.Paste")
			(roundrect_rratio 0.25)
			(net 1 "GND")
			(pintype "passive")
			(teardrops
				(best_length_ratio 0.2)
				(max_length 1)
				(best_width_ratio 0.9)
				(max_width 2)
				(curved_edges yes)
				(filter_ratio 0.9)
				(enabled yes)
				(allow_two_segments yes)
				(prefer_zone_connections yes)
			)
		)
		(pad "2" smd roundrect
			(at 0.48 0 90)
			(size 0.59 0.64)
			(layers "F.Cu" "F.Mask" "F.Paste")
			(roundrect_rratio 0.25)
			(net 625 "/PCIe redriver/TX_EQ2")
			(pintype "passive")
			(teardrops
				(best_length_ratio 0.2)
				(max_length 1)
				(best_width_ratio 0.9)
				(max_width 2)
				(curved_edges yes)
				(filter_ratio 0.9)
				(enabled yes)
				(allow_two_segments yes)
				(prefer_zone_connections yes)
			)
		)
	)
	(footprint "antmicro-footprints:C_0402_1005Metric"
		(layer "F.Cu")
		(at 118.9 148.421 -90)
		(descr "Capacitor SMD 0402")
		(tags "capacitor SMD 0402")
		(property "Reference" "C119"
			(at -12.611 -1.1 90)
			(layer "F.SilkS")
			(effects
				(font
					(size 0.7 0.7)
					(thickness 0.15)
				)
				(justify right bottom)
			)
		)
		(property "Value" "C_100n_0402"
			(at -1.022927 2.155213 90)
			(layer "F.Fab")
			(effects
				(font
					(size 0.7 0.7)
					(thickness 0.15)
				)
				(justify right bottom)
			)
		)
		(property "Datasheet" "https://www.murata.com/products/productdetail?partno=GRM155R61H104KE14%23"
			(at 0 0 270)
			(layer "F.Fab")
			(hide yes)
			(effects
				(font
					(size 1.27 1.27)
					(thickness 0.15)
				)
			)
		)
		(property "Author" "Antmicro"
			(at -29.521 267.321 0)
			(layer "F.Fab")
			(hide yes)
			(effects
				(font
					(size 1 1)
					(thickness 0.15)
				)
			)
		)
		(property "Dielectric" "X5R"
			(at -29.521 267.321 0)
			(layer "F.Fab")
			(hide yes)
			(effects
				(font
					(size 1 1)
					(thickness 0.15)
				)
			)
		)
		(property "License" "Apache-2.0"
			(at -29.521 267.321 0)
			(layer "F.Fab")
			(hide yes)
			(effects
				(font
					(size 1 1)
					(thickness 0.15)
				)
			)
		)
		(property "MPN" "GRM155R61H104KE14D"
			(at -29.521 267.321 0)
			(layer "F.Fab")
			(hide yes)
			(effects
				(font
					(size 1 1)
					(thickness 0.15)
				)
			)
		)
		(property "Manufacturer" "Murata"
			(at -29.521 267.321 0)
			(layer "F.Fab")
			(hide yes)
			(effects
				(font
					(size 1 1)
					(thickness 0.15)
				)
			)
		)
		(property "Public" "False"
			(at -29.521 267.321 0)
			(layer "F.Fab")
			(hide yes)
			(effects
				(font
					(size 1 1)
					(thickness 0.15)
				)
			)
		)
		(property "Val" "100n"
			(at -29.521 267.321 0)
			(layer "F.Fab")
			(hide yes)
			(effects
				(font
					(size 1 1)
					(thickness 0.15)
				)
			)
		)
		(property "Voltage" "50V"
			(at -29.521 267.321 0)
			(layer "F.Fab")
			(hide yes)
			(effects
				(font
					(size 1 1)
					(thickness 0.15)
				)
			)
		)
		(sheetname "PCIe redriver")
		(sheetfile "pcie_redriver.kicad_sch")
		(attr smd)
		(fp_rect
			(start -0.925 -0.47)
			(end 0.925 0.47)
			(stroke
				(width 0.05)
				(type default)
			)
			(fill no)
			(layer "F.CrtYd")
		)
		(fp_line
			(start -0.494 0.248)
			(end -0.494 -0.25)
			(stroke
				(width 0.15)
				(type solid)
			)
			(layer "F.Fab")
		)
		(fp_line
			(start 0.504 0.248)
			(end -0.494 0.248)
			(stroke
				(width 0.15)
				(type solid)
			)
			(layer "F.Fab")
		)
		(fp_line
			(start -0.494 -0.25)
			(end 0.504 -0.25)
			(stroke
				(width 0.15)
				(type solid)
			)
			(layer "F.Fab")
		)
		(fp_line
			(start 0.504 -0.25)
			(end 0.504 0.248)
			(stroke
				(width 0.15)
				(type solid)
			)
			(layer "F.Fab")
		)
		(pad "1" smd roundrect
			(at -0.48 0 270)
			(size 0.59 0.64)
			(layers "F.Cu" "F.Mask" "F.Paste")
			(roundrect_rratio 0.25)
			(net 1 "GND")
			(pintype "passive")
			(teardrops
				(best_length_ratio 0.2)
				(max_length 1)
				(best_width_ratio 0.9)
				(max_width 2)
				(curved_edges yes)
				(filter_ratio 0.9)
				(enabled yes)
				(allow_two_segments yes)
				(prefer_zone_connections yes)
			)
		)
		(pad "2" smd roundrect
			(at 0.48 0 270)
			(size 0.59 0.64)
			(layers "F.Cu" "F.Mask" "F.Paste")
			(roundrect_rratio 0.25)
			(net 2 "+3V3")
			(pintype "passive")
			(teardrops
				(best_length_ratio 0.2)
				(max_length 1)
				(best_width_ratio 0.9)
				(max_width 2)
				(curved_edges yes)
				(filter_ratio 0.9)
				(enabled yes)
				(allow_two_segments yes)
				(prefer_zone_connections yes)
			)
		)
	)
	(footprint "antmicro-footprints:C_0402_1005Metric"
		(layer "F.Cu")
		(at 302.575 140.185 -90)
		(descr "Capacitor SMD 0402")
		(tags "capacitor SMD 0402")
		(property "Reference" "C46"
			(at -0.875 0.525 90)
			(layer "F.SilkS")
			(effects
				(font
					(size 0.7 0.7)
					(thickness 0.15)
				)
				(justify right bottom)
			)
		)
		(property "Value" "C_1u_0402"
			(at -1.022927 2.155213 90)
			(layer "F.Fab")
			(effects
				(font
					(size 0.7 0.7)
					(thickness 0.15)
				)
				(justify right bottom)
			)
		)
		(property "Datasheet" "https://product.tdk.com/en/search/capacitor/ceramic/mlcc/info?part_no=C1005X6S1A105K050BC"
			(at 0 0 270)
			(layer "F.Fab")
			(hide yes)
			(effects
				(font
					(size 1.27 1.27)
					(thickness 0.15)
				)
			)
		)
		(property "Author" "Antmicro"
			(at 162.39 442.76 0)
			(layer "F.Fab")
			(hide yes)
			(effects
				(font
					(size 1 1)
					(thickness 0.15)
				)
			)
		)
		(property "Dielectric" ""
			(at 162.39 442.76 0)
			(layer "F.Fab")
			(hide yes)
			(effects
				(font
					(size 1 1)
					(thickness 0.15)
				)
			)
		)
		(property "License" "Apache-2.0"
			(at 162.39 442.76 0)
			(layer "F.Fab")
			(hide yes)
			(effects
				(font
					(size 1 1)
					(thickness 0.15)
				)
			)
		)
		(property "MPN" "C1005X6S1A105K050BC"
			(at 162.39 442.76 0)
			(layer "F.Fab")
			(hide yes)
			(effects
				(font
					(size 1 1)
					(thickness 0.15)
				)
			)
		)
		(property "Manufacturer" "TDK"
			(at 162.39 442.76 0)
			(layer "F.Fab")
			(hide yes)
			(effects
				(font
					(size 1 1)
					(thickness 0.15)
				)
			)
		)
		(property "Public" "False"
			(at 162.39 442.76 0)
			(layer "F.Fab")
			(hide yes)
			(effects
				(font
					(size 1 1)
					(thickness 0.15)
				)
			)
		)
		(property "Val" "1u"
			(at 162.39 442.76 0)
			(layer "F.Fab")
			(hide yes)
			(effects
				(font
					(size 1 1)
					(thickness 0.15)
				)
			)
		)
		(property "Voltage" ""
			(at 162.39 442.76 0)
			(layer "F.Fab")
			(hide yes)
			(effects
				(font
					(size 1 1)
					(thickness 0.15)
				)
			)
		)
		(sheetname "Power")
		(sheetfile "power.kicad_sch")
		(attr smd)
		(fp_rect
			(start -0.925 -0.47)
			(end 0.925 0.47)
			(stroke
				(width 0.05)
				(type default)
			)
			(fill no)
			(layer "F.CrtYd")
		)
		(fp_line
			(start -0.494 0.248)
			(end -0.494 -0.25)
			(stroke
				(width 0.15)
				(type solid)
			)
			(layer "F.Fab")
		)
		(fp_line
			(start 0.504 0.248)
			(end -0.494 0.248)
			(stroke
				(width 0.15)
				(type solid)
			)
			(layer "F.Fab")
		)
		(fp_line
			(start -0.494 -0.25)
			(end 0.504 -0.25)
			(stroke
				(width 0.15)
				(type solid)
			)
			(layer "F.Fab")
		)
		(fp_line
			(start 0.504 -0.25)
			(end 0.504 0.248)
			(stroke
				(width 0.15)
				(type solid)
			)
			(layer "F.Fab")
		)
		(pad "1" smd roundrect
			(at -0.48 0 270)
			(size 0.59 0.64)
			(layers "F.Cu" "F.Mask" "F.Paste")
			(roundrect_rratio 0.25)
			(net 1 "GND")
			(pintype "passive")
			(teardrops
				(best_length_ratio 0.2)
				(max_length 1)
				(best_width_ratio 0.9)
				(max_width 2)
				(curved_edges yes)
				(filter_ratio 0.9)
				(enabled yes)
				(allow_two_segments yes)
				(prefer_zone_connections yes)
			)
		)
		(pad "2" smd roundrect
			(at 0.48 0 270)
			(size 0.59 0.64)
			(layers "F.Cu" "F.Mask" "F.Paste")
			(roundrect_rratio 0.25)
			(net 65 "+12V")
			(pintype "passive")
			(teardrops
				(best_length_ratio 0.2)
				(max_length 1)
				(best_width_ratio 0.9)
				(max_width 2)
				(curved_edges yes)
				(filter_ratio 0.9)
				(enabled yes)
				(allow_two_segments yes)
				(prefer_zone_connections yes)
			)
		)
	)
	(footprint "antmicro-footprints:R_0402_1005Metric"
		(layer "F.Cu")
		(at 156.475 71.31 180)
		(descr "Resistor SMD 0402")
		(tags "resistor SMD 0402")
		(property "Reference" "R133"
			(at -3.65 -0.45 0)
			(layer "F.SilkS")
			(effects
				(font
					(size 0.7 0.7)
					(thickness 0.15)
				)
				(justify right bottom)
			)
		)
		(property "Value" "R_0R_0402"
			(at -1.011843 1.772047 0)
			(layer "F.Fab")
			(effects
				(font
					(size 0.7 0.7)
					(thickness 0.15)
				)
				(justify right bottom)
			)
		)
		(property "Datasheet" "https://industrial.panasonic.com/cdbs/www-data/pdf/RDA0000/AOA0000C301.pdf"
			(at 0 0 180)
			(layer "F.Fab")
			(hide yes)
			(effects
				(font
					(size 1.27 1.27)
					(thickness 0.15)
				)
			)
		)
		(property "Author" "Antmicro"
			(at 312.95 142.62 0)
			(layer "F.Fab")
			(hide yes)
			(effects
				(font
					(size 1 1)
					(thickness 0.15)
				)
			)
		)
		(property "Current" "1A"
			(at 312.95 142.62 0)
			(layer "F.Fab")
			(hide yes)
			(effects
				(font
					(size 1 1)
					(thickness 0.15)
				)
			)
		)
		(property "License" "Apache-2.0"
			(at 312.95 142.62 0)
			(layer "F.Fab")
			(hide yes)
			(effects
				(font
					(size 1 1)
					(thickness 0.15)
				)
			)
		)
		(property "MPN" "ERJ2GE0R00X"
			(at 312.95 142.62 0)
			(layer "F.Fab")
			(hide yes)
			(effects
				(font
					(size 1 1)
					(thickness 0.15)
				)
			)
		)
		(property "Manufacturer" "Panasonic"
			(at 312.95 142.62 0)
			(layer "F.Fab")
			(hide yes)
			(effects
				(font
					(size 1 1)
					(thickness 0.15)
				)
			)
		)
		(property "Public" "False"
			(at 312.95 142.62 0)
			(layer "F.Fab")
			(hide yes)
			(effects
				(font
					(size 1 1)
					(thickness 0.15)
				)
			)
		)
		(property "Tolerance" ""
			(at 312.95 142.62 0)
			(layer "F.Fab")
			(hide yes)
			(effects
				(font
					(size 1 1)
					(thickness 0.15)
				)
			)
		)
		(property "Val" "0R"
			(at 312.95 142.62 0)
			(layer "F.Fab")
			(hide yes)
			(effects
				(font
					(size 1 1)
					(thickness 0.15)
				)
			)
		)
		(sheetname "M.2 key E")
		(sheetfile "m2keye.kicad_sch")
		(attr smd)
		(fp_rect
			(start -0.925 -0.47)
			(end 0.925 0.47)
			(stroke
				(width 0.05)
				(type default)
			)
			(fill no)
			(layer "F.CrtYd")
		)
		(fp_rect
			(start -0.5 -0.25)
			(end 0.5 0.25)
			(stroke
				(width 0.15)
				(type solid)
			)
			(fill no)
			(layer "F.Fab")
		)
		(pad "1" smd roundrect
			(at -0.48 0 180)
			(size 0.59 0.64)
			(layers "F.Cu" "F.Mask" "F.Paste")
			(roundrect_rratio 0.25)
			(net 378 "/Com Express 7 Interfaces/USB1.D+")
			(pintype "passive")
			(teardrops
				(best_length_ratio 0.2)
				(max_length 1)
				(best_width_ratio 0.9)
				(max_width 2)
				(curved_edges yes)
				(filter_ratio 0.9)
				(enabled yes)
				(allow_two_segments yes)
				(prefer_zone_connections yes)
			)
		)
		(pad "2" smd roundrect
			(at 0.48 0 180)
			(size 0.59 0.64)
			(layers "F.Cu" "F.Mask" "F.Paste")
			(roundrect_rratio 0.25)
			(net 3 "/M.2 key E/WIFI_BT_USB_D_P")
			(pintype "passive")
			(teardrops
				(best_length_ratio 0.2)
				(max_length 1)
				(best_width_ratio 0.9)
				(max_width 2)
				(curved_edges yes)
				(filter_ratio 0.9)
				(enabled yes)
				(allow_two_segments yes)
				(prefer_zone_connections yes)
			)
		)
	)
	(footprint "antmicro-footprints:C_Pol_EIA-B"
		(layer "F.Cu")
		(at 308.825 135.8135)
		(property "Reference" "C65"
			(at -1.975 2.6465 0)
			(layer "F.SilkS")
			(effects
				(font
					(size 0.7 0.7)
					(thickness 0.15)
				)
				(justify left bottom)
			)
		)
		(property "Value" "C_Pol_100u_10V_KEMET-T520-B"
			(at -3.965 2.1265 0)
			(layer "F.Fab")
			(effects
				(font
					(size 0.7 0.7)
					(thickness 0.15)
				)
				(justify right bottom mirror)
			)
		)
		(property "Datasheet" "https://www.kemet.com/en/us/capacitors/product/T520B107M010ATE070.html"
			(at 0 0 0)
			(layer "F.Fab")
			(hide yes)
			(effects
				(font
					(size 1.27 1.27)
					(thickness 0.15)
				)
			)
		)
		(property "Author" "Antmicro"
			(at 0 0 0)
			(layer "F.Fab")
			(hide yes)
			(effects
				(font
					(size 1 1)
					(thickness 0.15)
				)
			)
		)
		(property "Dielectric" "template_dielectric"
			(at 0 0 0)
			(layer "F.Fab")
			(hide yes)
			(effects
				(font
					(size 1 1)
					(thickness 0.15)
				)
			)
		)
		(property "License" "Apache-2.0"
			(at 0 0 0)
			(layer "F.Fab")
			(hide yes)
			(effects
				(font
					(size 1 1)
					(thickness 0.15)
				)
			)
		)
		(property "MPN" "T520B107M010ATE070"
			(at 0 0 0)
			(layer "F.Fab")
			(hide yes)
			(effects
				(font
					(size 1 1)
					(thickness 0.15)
				)
			)
		)
		(property "Manufacturer" "KEMET"
			(at 0 0 0)
			(layer "F.Fab")
			(hide yes)
			(effects
				(font
					(size 1 1)
					(thickness 0.15)
				)
			)
		)
		(property "Public" "False"
			(at 0 0 0)
			(layer "F.Fab")
			(hide yes)
			(effects
				(font
					(size 1 1)
					(thickness 0.15)
				)
			)
		)
		(property "Val" "100u"
			(at 0 0 0)
			(layer "F.Fab")
			(hide yes)
			(effects
				(font
					(size 1 1)
					(thickness 0.15)
				)
			)
		)
		(property "Voltage" "10V"
			(at 0 0 0)
			(layer "F.Fab")
			(hide yes)
			(effects
				(font
					(size 1 1)
					(thickness 0.15)
				)
			)
		)
		(sheetname "Power")
		(sheetfile "power.kicad_sch")
		(attr smd)
		(fp_line
			(start -2.521 -1.676)
			(end -2.123 -1.676)
			(stroke
				(width 0.15)
				(type solid)
			)
			(layer "F.SilkS")
		)
		(fp_line
			(start -2.325 -1.475)
			(end -2.325 -1.878)
			(stroke
				(width 0.15)
				(type solid)
			)
			(layer "F.SilkS")
		)
		(fp_line
			(start -1.8 -1.6)
			(end 1.8 -1.6)
			(stroke
				(width 0.15)
				(type solid)
			)
			(layer "F.SilkS")
		)
		(fp_line
			(start -1.8 -1.3)
			(end -1.8 -1.6)
			(stroke
				(width 0.15)
				(type solid)
			)
			(layer "F.SilkS")
		)
		(fp_line
			(start -1.8 1.3)
			(end -1.8 1.6)
			(stroke
				(width 0.15)
				(type solid)
			)
			(layer "F.SilkS")
		)
		(fp_line
			(start 1.8 -1.3)
			(end 1.8 -1.6)
			(stroke
				(width 0.15)
				(type solid)
			)
			(layer "F.SilkS")
		)
		(fp_line
			(start 1.8 1.3)
			(end 1.8 1.6)
			(stroke
				(width 0.15)
				(type solid)
			)
			(layer "F.SilkS")
		)
		(fp_line
			(start 1.8 1.6)
			(end -1.8 1.6)
			(stroke
				(width 0.15)
				(type solid)
			)
			(layer "F.SilkS")
		)
		(fp_line
			(start -2.411 -1.35)
			(end -2.41 1.35)
			(stroke
				(width 0.05)
				(type solid)
			)
			(layer "F.CrtYd")
		)
		(fp_line
			(start -1.97 -1.75)
			(end -1.97 -1.35)
			(stroke
				(width 0.05)
				(type solid)
			)
			(layer "F.CrtYd")
		)
		(fp_line
			(start -1.97 -1.35)
			(end -2.41 -1.35)
			(stroke
				(width 0.05)
				(type solid)
			)
			(layer "F.CrtYd")
		)
		(fp_line
			(start -1.97 1.35)
			(end -2.41 1.35)
			(stroke
				(width 0.05)
				(type solid)
			)
			(layer "F.CrtYd")
		)
		(fp_line
			(start -1.97 1.35)
			(end -1.97 1.75)
			(stroke
				(width 0.05)
				(type solid)
			)
			(layer "F.CrtYd")
		)
		(fp_line
			(start 1.959 -1.75)
			(end -1.97 -1.75)
			(stroke
				(width 0.05)
				(type solid)
			)
			(layer "F.CrtYd")
		)
		(fp_line
			(start 1.959 -1.75)
			(end 1.959 -1.35)
			(stroke
				(width 0.05)
				(type solid)
			)
			(layer "F.CrtYd")
		)
		(fp_line
			(start 1.96 1.35)
			(end 1.96 1.75)
			(stroke
				(width 0.05)
				(type solid)
			)
			(layer "F.CrtYd")
		)
		(fp_line
			(start 1.96 1.75)
			(end -1.97 1.75)
			(stroke
				(width 0.05)
				(type solid)
			)
			(layer "F.CrtYd")
		)
		(fp_line
			(start 2.399 -1.35)
			(end 1.959 -1.35)
			(stroke
				(width 0.05)
				(type solid)
			)
			(layer "F.CrtYd")
		)
		(fp_line
			(start 2.399 -1.35)
			(end 2.4 1.35)
			(stroke
				(width 0.05)
				(type solid)
			)
			(layer "F.CrtYd")
		)
		(fp_line
			(start 2.4 1.35)
			(end 1.96 1.35)
			(stroke
				(width 0.05)
				(type solid)
			)
			(layer "F.CrtYd")
		)
		(fp_line
			(start -1.7 1.324)
			(end -1.551 1.475)
			(stroke
				(width 0.15)
				(type solid)
			)
			(layer "F.Fab")
		)
		(fp_rect
			(start -1.72 -1.5)
			(end 1.719 1.499)
			(stroke
				(width 0.15)
				(type solid)
			)
			(fill no)
			(layer "F.Fab")
		)
		(pad "1" smd roundrect
			(at -1.551 0)
			(size 1.2 2.2)
			(layers "F.Cu" "F.Mask" "F.Paste")
			(roundrect_rratio 0.1)
			(net 76 "Net-(C63-Pad2)")
			(pintype "passive")
			(teardrops
				(best_length_ratio 0.2)
				(max_length 1)
				(best_width_ratio 0.9)
				(max_width 2)
				(curved_edges yes)
				(filter_ratio 0.9)
				(enabled yes)
				(allow_two_segments yes)
				(prefer_zone_connections yes)
			)
		)
		(pad "2" smd roundrect
			(at 1.55 0)
			(size 1.2 2.2)
			(layers "F.Cu" "F.Mask" "F.Paste")
			(roundrect_rratio 0.1)
			(net 1 "GND")
			(pintype "passive")
			(teardrops
				(best_length_ratio 0.2)
				(max_length 1)
				(best_width_ratio 0.9)
				(max_width 2)
				(curved_edges yes)
				(filter_ratio 0.9)
				(enabled yes)
				(allow_two_segments yes)
				(prefer_zone_connections yes)
			)
		)
	)
)
